(kicad_pcb
	(version 20260206)
	(generator "pcbnew")
	(generator_version "10.0")
	(general
		(thickness 1.6)
		(legacy_teardrops no)
	)
	(paper "A4")
	(title_block
		(title "Wiwynn_Tioga_Pass_MB.brd")
		(comment 1 "Tioga Pass / footprints 4152-4159 of 4770")
	)
	(layers
		(0 "F.Cu" signal "TOP")
		(4 "In1.Cu" signal "L2GND")
		(6 "In2.Cu" signal "L3")
		(8 "In3.Cu" signal "L4GND")
		(10 "In4.Cu" signal "L5")
		(12 "In5.Cu" signal "L6GND")
		(14 "In6.Cu" signal "L7VCC")
		(16 "In7.Cu" signal "L8VCC")
		(18 "In8.Cu" signal "L9GND")
		(20 "In9.Cu" signal "L10")
		(22 "In10.Cu" signal "L11GND")
		(24 "In11.Cu" signal "L12")
		(26 "In12.Cu" signal "L13GND")
		(2 "B.Cu" signal "BOTTOM")
		(9 "F.Adhes" user "F.Adhesive")
		(11 "B.Adhes" user "B.Adhesive")
		(13 "F.Paste" user "Package Geometry/Pastemask Top")
		(15 "B.Paste" user "Package Geometry/Pastemask Bottom")
		(5 "F.SilkS" user "Ref Des/Silkscreen Top")
		(7 "B.SilkS" user "Ref Des/Silkscreen Bottom")
		(1 "F.Mask" user "Board Geometry/Soldermask Top")
		(3 "B.Mask" user "Board Geometry/Soldermask Bottom")
		(17 "Dwgs.User" user "User.Drawings")
		(19 "Cmts.User" user "User.Comments")
		(21 "Eco1.User" user "User.Eco1")
		(23 "Eco2.User" user "User.Eco2")
		(25 "Edge.Cuts" user "Board Geometry/Outline")
		(27 "Margin" user)
		(31 "F.CrtYd" user "Package Geometry/Place Bound Top")
		(29 "B.CrtYd" user "Package Geometry/Place Bound Bottom")
		(35 "F.Fab" user "Ref Des/Assembly Top")
		(33 "B.Fab" user "Ref Des/Assembly Bottom")
	)
	(footprint ""
		(layer "B.Cu")
		(at 33.689036 -93.818202 90)
		(property "Reference" "C1C3"
			(at 0 0 90)
			(layer "B.SilkS")
			(hide yes)
			(effects
				(font
					(size 1.27 1.27)
				)
				(justify mirror)
			)
		)
		(property "Value" "*"
			(at -1.1811 -2.8194 90)
			(unlocked yes)
			(layer "B.Fab")
			(hide yes)
			(effects
				(font
					(size 1.27 1.016)
					(thickness 0.1524)
				)
				(justify mirror)
			)
		)
		(property "Device Type" "SC1U10V2KX-4-GP_SMD-BCG6-SC1U1A"
			(at -1.1811 -4.3434 90)
			(unlocked yes)
			(layer "B.Fab")
			(hide yes)
			(effects
				(font
					(size 1.27 1.016)
					(thickness 0.1524)
				)
				(justify mirror)
			)
		)
		(duplicate_pad_numbers_are_jumpers no)
		(fp_rect
			(start 0.4318 0.9525)
			(end -0.4318 -0.9525)
			(stroke
				(width 0)
				(type default)
			)
			(fill no)
			(layer "B.CrtYd")
		)
		(fp_rect
			(start 0.4318 0.9525)
			(end -0.4318 -0.9525)
			(stroke
				(width 0)
				(type default)
			)
			(fill no)
			(layer "B.Fab")
		)
		(pad "1" smd custom
			(at 0 -0.4445 270)
			(size 0.1524 0.1524)
			(layers "B.Cu" "B.Mask" "B.Paste")
			(net "P5V_STBY")
			(options
				(clearance outline)
				(anchor circle)
			)
			(primitives
				(gr_poly
					(pts
						(arc
							(start 0.3048 0.2032)
							(mid 0.275042 0.275042)
							(end 0.2032 0.3048)
						)
						(arc
							(start -0.2032 0.3048)
							(mid -0.275042 0.275042)
							(end -0.3048 0.2032)
						)
						(arc
							(start -0.3048 -0.2032)
							(mid -0.275042 -0.275042)
							(end -0.2032 -0.3048)
						)
						(arc
							(start 0.2032 -0.3048)
							(mid 0.275042 -0.275042)
							(end 0.3048 -0.2032)
						)
					)
					(width 0)
					(fill yes)
				)
			)
		)
		(pad "2" smd custom
			(at 0 0.4445 270)
			(size 0.1524 0.1524)
			(layers "B.Cu" "B.Mask" "B.Paste")
			(net "GND")
			(options
				(clearance outline)
				(anchor circle)
			)
			(primitives
				(gr_poly
					(pts
						(arc
							(start 0.3048 0.2032)
							(mid 0.275042 0.275042)
							(end 0.2032 0.3048)
						)
						(arc
							(start -0.2032 0.3048)
							(mid -0.275042 0.275042)
							(end -0.3048 0.2032)
						)
						(arc
							(start -0.3048 -0.2032)
							(mid -0.275042 -0.275042)
							(end -0.2032 -0.3048)
						)
						(arc
							(start 0.2032 -0.3048)
							(mid 0.275042 -0.275042)
							(end 0.3048 -0.2032)
						)
					)
					(width 0)
					(fill yes)
				)
			)
		)
	)
	(footprint ""
		(layer "B.Cu")
		(at 484.124 -147.828 90)
		(property "Reference" "CR1L2"
			(at 0 0 90)
			(layer "B.SilkS")
			(hide yes)
			(effects
				(font
					(size 1.27 1.27)
				)
				(justify mirror)
			)
		)
		(property "Value" ""
			(at 0 0 90)
			(layer "B.Fab")
			(effects
				(font
					(size 1.27 1.27)
				)
				(justify mirror)
			)
		)
		(duplicate_pad_numbers_are_jumpers no)
		(fp_line
			(start 0.9144 0.1016)
			(end 0.9144 2.9464)
			(stroke
				(width 0.1524)
				(type default)
			)
			(layer "B.SilkS")
		)
		(fp_line
			(start 0.8382 0.1016)
			(end 0.9144 0.1016)
			(stroke
				(width 0.1524)
				(type default)
			)
			(layer "B.SilkS")
		)
		(fp_line
			(start -0.8382 0.1016)
			(end -0.9144 0.1016)
			(stroke
				(width 0.1524)
				(type default)
			)
			(layer "B.SilkS")
		)
		(fp_line
			(start -0.9144 0.1016)
			(end -0.9144 2.9464)
			(stroke
				(width 0.1524)
				(type default)
			)
			(layer "B.SilkS")
		)
		(fp_line
			(start 0.9144 2.9464)
			(end 0.8382 2.9464)
			(stroke
				(width 0.1524)
				(type default)
			)
			(layer "B.SilkS")
		)
		(fp_line
			(start -0.9144 2.9464)
			(end -0.8382 2.9464)
			(stroke
				(width 0.1524)
				(type default)
			)
			(layer "B.SilkS")
		)
		(fp_circle
			(center -1.128776 -0.907288)
			(end -1.128776 -0.780288)
			(stroke
				(width 0.254)
				(type default)
			)
			(fill no)
			(layer "B.SilkS")
		)
		(fp_poly
			(pts
				(xy 0 0.1016) (xy -0.5334 0.1016) (xy -0.7366 0.1016) (xy -0.9144 0.1016) (xy -0.9144 2.9464) (xy -0.8382 2.9464)
				(xy -0.762 2.9464) (xy 0.9144 2.9464) (xy 0.9144 2.7686) (xy 0.9144 2.159) (xy 0.9144 0.1016) (xy 0.7366 0.1016)
				(xy 0.5842 0.1016)
			)
			(stroke
				(width 0)
				(type default)
			)
			(fill no)
			(layer "B.CrtYd")
		)
		(fp_line
			(start 0.9144 0.1016)
			(end 0.9144 2.9464)
			(stroke
				(width 0.1)
				(type default)
			)
			(layer "B.Fab")
		)
		(fp_line
			(start -0.9144 0.1016)
			(end 0.9144 0.1016)
			(stroke
				(width 0.1)
				(type default)
			)
			(layer "B.Fab")
		)
		(fp_line
			(start 0.9144 2.9464)
			(end -0.9144 2.9464)
			(stroke
				(width 0.1)
				(type default)
			)
			(layer "B.Fab")
		)
		(fp_line
			(start -0.9144 2.9464)
			(end -0.9144 0.1016)
			(stroke
				(width 0.1)
				(type default)
			)
			(layer "B.Fab")
		)
		(fp_circle
			(center -1.128776 -0.907288)
			(end -1.128776 -0.780288)
			(stroke
				(width 0.254)
				(type default)
			)
			(fill no)
			(layer "B.Fab")
		)
		(pad "1" smd rect
			(at 0 0)
			(size 1.524 0.762)
			(layers "B.Cu" "B.Mask" "B.Paste")
			(net "FM_DB_UART_SEL2_N")
		)
		(pad "2" smd rect
			(at 0 3.048 180)
			(size 1.524 0.762)
			(layers "B.Cu" "B.Mask" "B.Paste")
			(net "FM_DB_UART_SEL1_N")
		)
	)
	(footprint ""
		(layer "B.Cu")
		(at 155.194 -8.128 90)
		(property "Reference" "C7U3"
			(at 0 0 90)
			(layer "B.SilkS")
			(hide yes)
			(effects
				(font
					(size 1.27 1.27)
				)
				(justify mirror)
			)
		)
		(property "Value" ""
			(at 0 0 90)
			(layer "B.Fab")
			(effects
				(font
					(size 1.27 1.27)
				)
				(justify mirror)
			)
		)
		(duplicate_pad_numbers_are_jumpers no)
		(fp_poly
			(pts
				(xy 0.4953 -0.2032) (xy -0.4953 -0.2032) (xy -0.4953 1.6002) (xy 0.4953 1.6002)
			)
			(stroke
				(width 0)
				(type default)
			)
			(fill no)
			(layer "B.CrtYd")
		)
		(fp_line
			(start 0.4953 -0.2032)
			(end -0.4953 -0.2032)
			(stroke
				(width 0.1)
				(type default)
			)
			(layer "B.Fab")
		)
		(fp_line
			(start -0.4953 -0.2032)
			(end -0.4953 1.6002)
			(stroke
				(width 0.1)
				(type default)
			)
			(layer "B.Fab")
		)
		(fp_line
			(start 0.4953 1.6002)
			(end 0.4953 -0.2032)
			(stroke
				(width 0.1)
				(type default)
			)
			(layer "B.Fab")
		)
		(fp_line
			(start -0.4953 1.6002)
			(end 0.4953 1.6002)
			(stroke
				(width 0.1)
				(type default)
			)
			(layer "B.Fab")
		)
		(pad "1" smd rect
			(at 0 0 270)
			(size 0.762 0.889)
			(layers "B.Cu" "B.Mask" "B.Paste")
			(net "PVPP_GHJ")
		)
		(pad "2" smd rect
			(at 0 1.397 270)
			(size 0.762 0.889)
			(layers "B.Cu" "B.Mask" "B.Paste")
			(net "GND")
		)
		(zone
			(layer "B.Cu")
			(hatch none 0.5)
			(connect_pads
				(clearance 0)
			)
			(min_thickness 0.25)
			(keepout
				(tracks not_allowed)
				(vias allowed)
				(pads allowed)
				(copperpour not_allowed)
				(footprints allowed)
			)
			(placement
				(enabled no)
				(sheetname "")
			)
			(fill
				(thermal_gap 0.5)
				(thermal_bridge_width 0.5)
				(island_removal_mode 0)
			)
			(polygon
				(pts
					(xy 155.6385 -8.509) (xy 155.6385 -7.747) (xy 156.1465 -7.747) (xy 156.1465 -8.509)
				)
			)
		)
	)
	(footprint ""
		(layer "B.Cu")
		(at 32.832802 -98.937064 90)
		(property "Reference" "C9N19"
			(at 0 0 90)
			(layer "B.SilkS")
			(hide yes)
			(effects
				(font
					(size 1.27 1.27)
				)
				(justify mirror)
			)
		)
		(property "Value" ""
			(at 0 0 90)
			(layer "B.Fab")
			(effects
				(font
					(size 1.27 1.27)
				)
				(justify mirror)
			)
		)
		(duplicate_pad_numbers_are_jumpers no)
		(fp_poly
			(pts
				(xy 0.7239 -0.2159) (xy -0.7239 -0.2159) (xy -0.7239 1.9939) (xy 0.7239 1.9939)
			)
			(stroke
				(width 0)
				(type default)
			)
			(fill no)
			(layer "B.CrtYd")
		)
		(fp_line
			(start 0.7239 -0.2159)
			(end 0.7239 1.9939)
			(stroke
				(width 0.1)
				(type default)
			)
			(layer "B.Fab")
		)
		(fp_line
			(start -0.7239 -0.2159)
			(end 0.7239 -0.2159)
			(stroke
				(width 0.1)
				(type default)
			)
			(layer "B.Fab")
		)
		(fp_line
			(start 0.7239 1.9939)
			(end -0.7239 1.9939)
			(stroke
				(width 0.1)
				(type default)
			)
			(layer "B.Fab")
		)
		(fp_line
			(start -0.7239 1.9939)
			(end -0.7239 -0.2159)
			(stroke
				(width 0.1)
				(type default)
			)
			(layer "B.Fab")
		)
		(pad "1" smd rect
			(at 0 0 270)
			(size 1.27 1.016)
			(layers "B.Cu" "B.Mask" "B.Paste")
			(net "VR_FET_SW_P12V_STBY_PVCCIN_CPU1")
		)
		(pad "2" smd rect
			(at 0 1.778 270)
			(size 1.27 1.016)
			(layers "B.Cu" "B.Mask" "B.Paste")
			(net "GND")
		)
		(zone
			(layer "B.Cu")
			(hatch none 0.5)
			(connect_pads
				(clearance 0)
			)
			(min_thickness 0.25)
			(keepout
				(tracks not_allowed)
				(vias allowed)
				(pads allowed)
				(copperpour not_allowed)
				(footprints allowed)
			)
			(placement
				(enabled no)
				(sheetname "")
			)
			(fill
				(thermal_gap 0.5)
				(thermal_bridge_width 0.5)
				(island_removal_mode 0)
			)
			(polygon
				(pts
					(xy 33.340802 -99.572064) (xy 33.340802 -98.302064) (xy 34.102802 -98.302064) (xy 34.102802 -99.572064)
				)
			)
		)
	)
	(footprint ""
		(layer "B.Cu")
		(at 417.006024 -141.732)
		(property "Reference" "R2L22"
			(at 0 0 0)
			(layer "B.SilkS")
			(hide yes)
			(effects
				(font
					(size 1.27 1.27)
				)
				(justify mirror)
			)
		)
		(property "Value" ""
			(at 0 0 0)
			(layer "B.Fab")
			(effects
				(font
					(size 1.27 1.27)
				)
				(justify mirror)
			)
		)
		(duplicate_pad_numbers_are_jumpers no)
		(fp_poly
			(pts
				(xy 0.2794 -0.1016) (xy -0.2794 -0.1016) (xy -0.2794 0.9906) (xy 0.2794 0.9906)
			)
			(stroke
				(width 0)
				(type default)
			)
			(fill no)
			(layer "B.CrtYd")
		)
		(fp_line
			(start -0.2794 -0.1016)
			(end 0.2794 -0.1016)
			(stroke
				(width 0.1)
				(type default)
			)
			(layer "B.Fab")
		)
		(fp_line
			(start -0.2794 0.9906)
			(end -0.2794 -0.1016)
			(stroke
				(width 0.1)
				(type default)
			)
			(layer "B.Fab")
		)
		(fp_line
			(start 0.2794 -0.1016)
			(end 0.2794 0.9906)
			(stroke
				(width 0.1)
				(type default)
			)
			(layer "B.Fab")
		)
		(fp_line
			(start 0.2794 0.9906)
			(end -0.2794 0.9906)
			(stroke
				(width 0.1)
				(type default)
			)
			(layer "B.Fab")
		)
		(pad "1" smd rect
			(at 0 0 180)
			(size 0.508 0.508)
			(layers "B.Cu" "B.Mask" "B.Paste")
			(net "PD_SATA1_CONTROLLER_TYPE_R")
		)
		(pad "2" smd rect
			(at 0 0.889 180)
			(size 0.508 0.508)
			(layers "B.Cu" "B.Mask" "B.Paste")
			(net "GND")
		)
		(zone
			(layer "B.Cu")
			(hatch none 0.5)
			(connect_pads
				(clearance 0)
			)
			(min_thickness 0.25)
			(keepout
				(tracks allowed)
				(vias not_allowed)
				(pads allowed)
				(copperpour not_allowed)
				(footprints allowed)
			)
			(placement
				(enabled no)
				(sheetname "")
			)
			(fill
				(thermal_gap 0.5)
				(thermal_bridge_width 0.5)
				(island_removal_mode 0)
			)
			(polygon
				(pts
					(xy 417.260024 -141.478) (xy 416.752024 -141.478) (xy 416.752024 -141.097) (xy 417.260024 -141.097)
				)
			)
		)
		(zone
			(layer "B.Cu")
			(hatch none 0.5)
			(connect_pads
				(clearance 0)
			)
			(min_thickness 0.25)
			(keepout
				(tracks not_allowed)
				(vias allowed)
				(pads allowed)
				(copperpour not_allowed)
				(footprints allowed)
			)
			(placement
				(enabled no)
				(sheetname "")
			)
			(fill
				(thermal_gap 0.5)
				(thermal_bridge_width 0.5)
				(island_removal_mode 0)
			)
			(polygon
				(pts
					(xy 417.260024 -141.097) (xy 416.752024 -141.097) (xy 416.752024 -141.478) (xy 417.260024 -141.478)
				)
			)
		)
	)
	(footprint ""
		(layer "B.Cu")
		(at 3.82524 -11.392916 90)
		(property "Reference" "C9U3"
			(at 0 0 90)
			(layer "B.SilkS")
			(hide yes)
			(effects
				(font
					(size 1.27 1.27)
				)
				(justify mirror)
			)
		)
		(property "Value" ""
			(at 0 0 90)
			(layer "B.Fab")
			(effects
				(font
					(size 1.27 1.27)
				)
				(justify mirror)
			)
		)
		(duplicate_pad_numbers_are_jumpers no)
		(fp_rect
			(start -0.7239 -0.2159)
			(end 0.7239 1.9939)
			(stroke
				(width 0)
				(type default)
			)
			(fill no)
			(layer "B.CrtYd")
		)
		(fp_line
			(start 0.7239 -0.2159)
			(end 0.7239 1.9939)
			(stroke
				(width 0.1)
				(type default)
			)
			(layer "B.Fab")
		)
		(fp_line
			(start -0.7239 -0.2159)
			(end 0.7239 -0.2159)
			(stroke
				(width 0.1)
				(type default)
			)
			(layer "B.Fab")
		)
		(fp_line
			(start 0.7239 1.9939)
			(end -0.7239 1.9939)
			(stroke
				(width 0.1)
				(type default)
			)
			(layer "B.Fab")
		)
		(fp_line
			(start -0.7239 1.9939)
			(end -0.7239 -0.2159)
			(stroke
				(width 0.1)
				(type default)
			)
			(layer "B.Fab")
		)
		(pad "1" smd rect
			(at 0 0 270)
			(size 1.27 1.016)
			(layers "B.Cu" "B.Mask" "B.Paste")
			(net "VR_FET_SW_P12V_STBY_PVDDQ_GHJ")
		)
		(pad "2" smd rect
			(at 0 1.778 270)
			(size 1.27 1.016)
			(layers "B.Cu" "B.Mask" "B.Paste")
			(net "GND")
		)
		(zone
			(layer "B.Cu")
			(hatch none 0.5)
			(connect_pads
				(clearance 0)
			)
			(min_thickness 0.25)
			(keepout
				(tracks not_allowed)
				(vias allowed)
				(pads allowed)
				(copperpour not_allowed)
				(footprints allowed)
			)
			(placement
				(enabled no)
				(sheetname "")
			)
			(fill
				(thermal_gap 0.5)
				(thermal_bridge_width 0.5)
				(island_removal_mode 0)
			)
			(polygon
				(pts
					(xy 4.33324 -10.757916) (xy 5.09524 -10.757916) (xy 5.09524 -12.027916) (xy 4.33324 -12.027916)
				)
			)
		)
	)
	(footprint ""
		(layer "B.Cu")
		(at 166.5097 -1.90246 180)
		(property "Reference" "C6W12"
			(at -1.47828 0.78994 270)
			(unlocked yes)
			(layer "B.SilkS")
			(effects
				(font
					(size 0.4064 0.254)
					(thickness 0.1524)
				)
				(justify mirror)
			)
		)
		(property "Value" ""
			(at 0 0 0)
			(layer "B.Fab")
			(effects
				(font
					(size 1.27 1.27)
				)
				(justify mirror)
			)
		)
		(duplicate_pad_numbers_are_jumpers no)
		(fp_poly
			(pts
				(xy 0.7239 -0.2159) (xy -0.7239 -0.2159) (xy -0.7239 1.9939) (xy 0.7239 1.9939)
			)
			(stroke
				(width 0)
				(type default)
			)
			(fill no)
			(layer "B.CrtYd")
		)
		(fp_line
			(start 0.7239 1.9939)
			(end -0.7239 1.9939)
			(stroke
				(width 0.1)
				(type default)
			)
			(layer "B.Fab")
		)
		(fp_line
			(start 0.7239 -0.2159)
			(end 0.7239 1.9939)
			(stroke
				(width 0.1)
				(type default)
			)
			(layer "B.Fab")
		)
		(fp_line
			(start -0.7239 1.9939)
			(end -0.7239 -0.2159)
			(stroke
				(width 0.1)
				(type default)
			)
			(layer "B.Fab")
		)
		(fp_line
			(start -0.7239 -0.2159)
			(end 0.7239 -0.2159)
			(stroke
				(width 0.1)
				(type default)
			)
			(layer "B.Fab")
		)
		(pad "1" smd rect
			(at 0 0)
			(size 1.27 1.016)
			(layers "B.Cu" "B.Mask" "B.Paste")
			(net "PVTT_GHJ")
		)
		(pad "2" smd rect
			(at 0 1.778)
			(size 1.27 1.016)
			(layers "B.Cu" "B.Mask" "B.Paste")
			(net "GND")
		)
		(zone
			(layer "B.Cu")
			(hatch none 0.5)
			(connect_pads
				(clearance 0)
			)
			(min_thickness 0.25)
			(keepout
				(tracks not_allowed)
				(vias allowed)
				(pads allowed)
				(copperpour not_allowed)
				(footprints allowed)
			)
			(placement
				(enabled no)
				(sheetname "")
			)
			(fill
				(thermal_gap 0.5)
				(thermal_bridge_width 0.5)
				(island_removal_mode 0)
			)
			(polygon
				(pts
					(xy 165.8747 -2.41046) (xy 167.1447 -2.41046) (xy 167.1447 -3.17246) (xy 165.8747 -3.17246)
				)
			)
		)
	)
	(footprint ""
		(layer "B.Cu")
		(at 258.1402 -12.827 -90)
		(property "Reference" "C5G45"
			(at -1.14681 0.76708 0)
			(unlocked yes)
			(layer "B.SilkS")
			(effects
				(font
					(size 0.7874 0.5842)
					(thickness 0.1524)
				)
				(justify mirror)
			)
		)
		(property "Value" ""
			(at 0 0 90)
			(layer "B.Fab")
			(effects
				(font
					(size 1.27 1.27)
				)
				(justify mirror)
			)
		)
		(duplicate_pad_numbers_are_jumpers no)
		(fp_rect
			(start -0.4953 -0.2032)
			(end 0.4953 1.6002)
			(stroke
				(width 0)
				(type default)
			)
			(fill no)
			(layer "B.CrtYd")
		)
		(fp_line
			(start -0.4953 1.6002)
			(end 0.4953 1.6002)
			(stroke
				(width 0.1)
				(type default)
			)
			(layer "B.Fab")
		)
		(fp_line
			(start 0.4953 1.6002)
			(end 0.4953 -0.2032)
			(stroke
				(width 0.1)
				(type default)
			)
			(layer "B.Fab")
		)
		(fp_line
			(start -0.4953 -0.2032)
			(end -0.4953 1.6002)
			(stroke
				(width 0.1)
				(type default)
			)
			(layer "B.Fab")
		)
		(fp_line
			(start 0.4953 -0.2032)
			(end -0.4953 -0.2032)
			(stroke
				(width 0.1)
				(type default)
			)
			(layer "B.Fab")
		)
		(pad "1" smd rect
			(at 0 0 90)
			(size 0.762 0.889)
			(layers "B.Cu" "B.Mask" "B.Paste")
			(net "PVDDQ_ABC")
		)
		(pad "2" smd rect
			(at 0 1.397 90)
			(size 0.762 0.889)
			(layers "B.Cu" "B.Mask" "B.Paste")
			(net "GND")
		)
		(zone
			(layer "B.Cu")
			(hatch none 0.5)
			(connect_pads
				(clearance 0)
			)
			(min_thickness 0.25)
			(keepout
				(tracks not_allowed)
				(vias allowed)
				(pads allowed)
				(copperpour not_allowed)
				(footprints allowed)
			)
			(placement
				(enabled no)
				(sheetname "")
			)
			(fill
				(thermal_gap 0.5)
				(thermal_bridge_width 0.5)
				(island_removal_mode 0)
			)
			(polygon
				(pts
					(xy 257.6957 -13.208) (xy 257.1877 -13.208) (xy 257.1877 -12.446) (xy 257.6957 -12.446)
				)
			)
		)
	)
)
